# S9S_MB_2U (Grand Teton) — schematic netlist excerpt (pin names and nets, part order shuffled) for the footprints in the layout excerpt that follows; sources: Cadence DE-HDL packaged netlist, KiCad conversion of 03242023_DA0F0TMBIJ0_F0T_Motherboard_J_brd_V01_OCP.brd

D43  SCHOTTKY_12  B0530WS7F IC  pkg SOD323XB  page 115 : A = PWRGD_FAIL_CPU0_CD_R1 ; C = P3V3_AUX
R94  Q_RES  240 1% EMPTY  pkg 0402LF  page 126 : A = PVNN_TERM_CPU0 ; B = PU_CPU0_UPI0_AC_COUPLING

(kicad_pcb
	(version 20260206)
	(generator "pcbnew")
	(generator_version "10.0")
	(general
		(thickness 1.6)
		(legacy_teardrops no)
	)
	(paper "A4")
	(title_block
		(title "03242023_DA0F0TMBIJ0_F0T_Motherboard_J_brd_V01_OCP.brd")
		(comment 1 "Grand Teton / footprints 5887-5888 of 6105")
	)
	(layers
		(0 "F.Cu" signal "TOP")
		(4 "In1.Cu" signal "GND")
		(6 "In2.Cu" signal "IN1")
		(8 "In3.Cu" signal "GND1")
		(10 "In4.Cu" signal "IN2")
		(12 "In5.Cu" signal "GND2")
		(14 "In6.Cu" signal "IN3")
		(16 "In7.Cu" signal "GND3")
		(18 "In8.Cu" signal "VCC")
		(20 "In9.Cu" signal "VCC1")
		(22 "In10.Cu" signal "GND4")
		(24 "In11.Cu" signal "IN4")
		(26 "In12.Cu" signal "GND5")
		(28 "In13.Cu" signal "IN5")
		(30 "In14.Cu" signal "GND6")
		(32 "In15.Cu" signal "IN6")
		(34 "In16.Cu" signal "GND7")
		(2 "B.Cu" signal "BOTTOM")
		(9 "F.Adhes" user "F.Adhesive")
		(11 "B.Adhes" user "B.Adhesive")
		(13 "F.Paste" user "Package Geometry/Pastemask Top")
		(15 "B.Paste" user "Package Geometry/Pastemask Bottom")
		(5 "F.SilkS" user "Ref Des/Silkscreen Top")
		(7 "B.SilkS" user "Ref Des/Silkscreen Bottom")
		(1 "F.Mask" user "Board Geometry/Soldermask Top")
		(3 "B.Mask" user "Board Geometry/Soldermask Bottom")
		(17 "Dwgs.User" user "User.Drawings")
		(19 "Cmts.User" user "User.Comments")
		(21 "Eco1.User" user "User.Eco1")
		(23 "Eco2.User" user "User.Eco2")
		(25 "Edge.Cuts" user "Board Geometry/Outline")
		(27 "Margin" user)
		(31 "F.CrtYd" user "Package Geometry/Place Bound Top")
		(29 "B.CrtYd" user "Package Geometry/Place Bound Bottom")
		(35 "F.Fab" user "Ref Des/Assembly Top")
		(33 "B.Fab" user "Ref Des/Assembly Bottom")
	)
	(footprint ""
		(layer "B.Cu")
		(at 286.275526 -315.46673 -90)
		(property "Reference" "D43"
			(at 1.767332 3.355086 0)
			(unlocked yes)
			(layer "B.SilkS")
			(effects
				(font
					(size 0.7874 0.5842)
					(thickness 0.1524)
				)
				(justify left mirror)
			)
		)
		(property "Value" ""
			(at 0 0 90)
			(layer "B.Fab")
			(effects
				(font
					(size 1.27 1.27)
				)
				(justify mirror)
			)
		)
		(duplicate_pad_numbers_are_jumpers no)
		(fp_line
			(start -2.050796 0.700024)
			(end 2.050796 0.700024)
			(stroke
				(width 0.1524)
				(type default)
			)
			(layer "B.SilkS")
		)
		(fp_line
			(start 2.050796 0.700024)
			(end 2.050796 -0.700024)
			(stroke
				(width 0.1524)
				(type default)
			)
			(layer "B.SilkS")
		)
		(fp_line
			(start -2.343404 0.6985)
			(end -2.216404 0.6985)
			(stroke
				(width 0.1524)
				(type default)
			)
			(layer "B.SilkS")
		)
		(fp_line
			(start -2.229104 0.6985)
			(end -2.051304 0.6985)
			(stroke
				(width 0.1524)
				(type default)
			)
			(layer "B.SilkS")
		)
		(fp_line
			(start -2.051304 0.6985)
			(end -2.051304 0.635)
			(stroke
				(width 0.1524)
				(type default)
			)
			(layer "B.SilkS")
		)
		(fp_line
			(start -2.152904 0.635)
			(end -2.152904 -0.6985)
			(stroke
				(width 0.1524)
				(type default)
			)
			(layer "B.SilkS")
		)
		(fp_line
			(start -2.051304 0.635)
			(end -2.152904 0.635)
			(stroke
				(width 0.1524)
				(type default)
			)
			(layer "B.SilkS")
		)
		(fp_line
			(start 0.30607 0.500126)
			(end -0.193802 0)
			(stroke
				(width 0.1524)
				(type default)
			)
			(layer "B.SilkS")
		)
		(fp_line
			(start -0.193802 0)
			(end 0.30607 -0.500126)
			(stroke
				(width 0.1524)
				(type default)
			)
			(layer "B.SilkS")
		)
		(fp_line
			(start -0.293878 -0.500126)
			(end -0.293878 0.500126)
			(stroke
				(width 0.1524)
				(type default)
			)
			(layer "B.SilkS")
		)
		(fp_line
			(start 0.30607 -0.500126)
			(end 0.30607 0.500126)
			(stroke
				(width 0.1524)
				(type default)
			)
			(layer "B.SilkS")
		)
		(fp_line
			(start -2.064004 -0.6731)
			(end -2.064004 -0.6985)
			(stroke
				(width 0.1524)
				(type default)
			)
			(layer "B.SilkS")
		)
		(fp_line
			(start -2.343404 -0.6985)
			(end -2.343404 0.6985)
			(stroke
				(width 0.1524)
				(type default)
			)
			(layer "B.SilkS")
		)
		(fp_line
			(start -2.229104 -0.6985)
			(end -2.229104 0.6985)
			(stroke
				(width 0.1524)
				(type default)
			)
			(layer "B.SilkS")
		)
		(fp_line
			(start -2.152904 -0.6985)
			(end -2.343404 -0.6985)
			(stroke
				(width 0.1524)
				(type default)
			)
			(layer "B.SilkS")
		)
		(fp_line
			(start -2.064004 -0.6985)
			(end -2.229104 -0.6985)
			(stroke
				(width 0.1524)
				(type default)
			)
			(layer "B.SilkS")
		)
		(fp_line
			(start -2.050796 -0.700024)
			(end -2.050796 0.700024)
			(stroke
				(width 0.1524)
				(type default)
			)
			(layer "B.SilkS")
		)
		(fp_line
			(start 2.050796 -0.700024)
			(end -2.050796 -0.700024)
			(stroke
				(width 0.1524)
				(type default)
			)
			(layer "B.SilkS")
		)
		(fp_line
			(start -0.899922 0.700024)
			(end 0.899922 0.700024)
			(stroke
				(width 0.1)
				(type default)
			)
			(layer "B.Fab")
		)
		(fp_line
			(start 0.899922 0.700024)
			(end 0.899922 -0.700024)
			(stroke
				(width 0.1)
				(type default)
			)
			(layer "B.Fab")
		)
		(fp_line
			(start -0.899922 -0.700024)
			(end -0.899922 0.700024)
			(stroke
				(width 0.1)
				(type default)
			)
			(layer "B.Fab")
		)
		(fp_line
			(start 0.899922 -0.700024)
			(end -0.899922 -0.700024)
			(stroke
				(width 0.1)
				(type default)
			)
			(layer "B.Fab")
		)
		(fp_text user "+"
			(at 3.123946 0.762 180)
			(unlocked yes)
			(layer "B.SilkS")
			(effects
				(font
					(size 1.905 1.4224)
					(thickness 0.1524)
				)
				(justify left mirror)
			)
		)
		(fp_text user "-"
			(at -1.345438 -1.784604 90)
			(unlocked yes)
			(layer "B.SilkS")
			(effects
				(font
					(size 1.905 1.4224)
					(thickness 0.1524)
				)
				(justify left mirror)
			)
		)
		(fp_text user "+"
			(at 3.123946 0.762 180)
			(unlocked yes)
			(layer "B.Fab")
			(effects
				(font
					(size 1.905 1.4224)
					(thickness 0.1524)
				)
				(justify left mirror)
			)
		)
		(fp_text user "-"
			(at -3.880104 0.23495 90)
			(unlocked yes)
			(layer "B.Fab")
			(effects
				(font
					(size 1.905 1.4224)
					(thickness 0.1524)
				)
				(justify left mirror)
			)
		)
		(pad "1" smd rect
			(at 1.199896 0 180)
			(size 0.6604 1.3716)
			(layers "B.Cu" "B.Mask" "B.Paste")
			(net "PWRGD_FAIL_CPU0_CD_R1")
		)
		(pad "2" smd rect
			(at -1.199896 0)
			(size 0.6604 1.3716)
			(layers "B.Cu" "B.Mask" "B.Paste")
			(net "P3V3_AUX")
		)
	)
	(footprint ""
		(layer "B.Cu")
		(at 315.53404 -193.53911 -90)
		(property "Reference" "R94"
			(at 0 0 90)
			(layer "B.SilkS")
			(hide yes)
			(effects
				(font
					(size 1.27 1.27)
				)
				(justify mirror)
			)
		)
		(property "Value" ""
			(at 0 0 90)
			(layer "B.Fab")
			(effects
				(font
					(size 1.27 1.27)
				)
				(justify mirror)
			)
		)
		(duplicate_pad_numbers_are_jumpers no)
		(fp_line
			(start -0.7874 0.4064)
			(end 0.7874 0.4064)
			(stroke
				(width 0.1524)
				(type default)
			)
			(layer "B.SilkS")
		)
		(fp_line
			(start 0.7874 0.4064)
			(end 0.7874 -0.4064)
			(stroke
				(width 0.1524)
				(type default)
			)
			(layer "B.SilkS")
		)
		(fp_line
			(start -0.7874 -0.4064)
			(end -0.7874 0.4064)
			(stroke
				(width 0.1524)
				(type default)
			)
			(layer "B.SilkS")
		)
		(fp_line
			(start 0.7874 -0.4064)
			(end -0.7874 -0.4064)
			(stroke
				(width 0.1524)
				(type default)
			)
			(layer "B.SilkS")
		)
		(fp_line
			(start -0.67945 0.3048)
			(end -0.120396 0.3048)
			(stroke
				(width 0.1)
				(type default)
			)
			(layer "B.Fab")
		)
		(fp_line
			(start -0.120396 0.3048)
			(end -0.120396 0.2794)
			(stroke
				(width 0.1)
				(type default)
			)
			(layer "B.Fab")
		)
		(fp_line
			(start 0.12065 0.3048)
			(end 0.67945 0.3048)
			(stroke
				(width 0.1)
				(type default)
			)
			(layer "B.Fab")
		)
		(fp_line
			(start 0.67945 0.3048)
			(end 0.67945 -0.305054)
			(stroke
				(width 0.1)
				(type default)
			)
			(layer "B.Fab")
		)
		(fp_line
			(start -0.120396 0.2794)
			(end 0.12065 0.2794)
			(stroke
				(width 0.1)
				(type default)
			)
			(layer "B.Fab")
		)
		(fp_line
			(start 0.12065 0.2794)
			(end 0.12065 0.3048)
			(stroke
				(width 0.1)
				(type default)
			)
			(layer "B.Fab")
		)
		(fp_line
			(start -0.12065 -0.2794)
			(end -0.12065 -0.3048)
			(stroke
				(width 0.1)
				(type default)
			)
			(layer "B.Fab")
		)
		(fp_line
			(start 0.12065 -0.2794)
			(end -0.12065 -0.2794)
			(stroke
				(width 0.1)
				(type default)
			)
			(layer "B.Fab")
		)
		(fp_line
			(start -0.67945 -0.3048)
			(end -0.67945 0.3048)
			(stroke
				(width 0.1)
				(type default)
			)
			(layer "B.Fab")
		)
		(fp_line
			(start -0.12065 -0.3048)
			(end -0.67945 -0.3048)
			(stroke
				(width 0.1)
				(type default)
			)
			(layer "B.Fab")
		)
		(fp_line
			(start 0.12065 -0.305054)
			(end 0.12065 -0.2794)
			(stroke
				(width 0.1)
				(type default)
			)
			(layer "B.Fab")
		)
		(fp_line
			(start 0.67945 -0.305054)
			(end 0.12065 -0.305054)
			(stroke
				(width 0.1)
				(type default)
			)
			(layer "B.Fab")
		)
		(pad "1" smd circle
			(at 0.40005 0 90)
			(size 0 0)
			(layers "B.Cu" "B.Mask" "B.Paste")
			(net "PVNN_TERM_CPU0")
		)
		(pad "2" smd circle
			(at -0.40005 0 90)
			(size 0 0)
			(layers "B.Cu" "B.Mask" "B.Paste")
			(net "PU_CPU0_UPI0_AC_COUPLING")
		)
	)
)
